(kicad_pcb
	(version 20260206)
	(generator "pcbnew")
	(generator_version "10.0")
	(general
		(thickness 1.6)
		(legacy_teardrops no)
	)
	(paper "A4")
	(title_block
		(title "Bryce Canyon_IOM_M2_16342-2_OCP.brd")
		(comment 1 "Bryce Canyon / footprints 470-476 of 1146")
	)
	(layers
		(0 "F.Cu" signal "TOP")
		(4 "In1.Cu" signal "L2GND")
		(6 "In2.Cu" signal "L3")
		(8 "In3.Cu" signal "L4VCC")
		(10 "In4.Cu" signal "L5VCC")
		(12 "In5.Cu" signal "L6")
		(14 "In6.Cu" signal "L7GND")
		(2 "B.Cu" signal "BOTTOM")
		(9 "F.Adhes" user "F.Adhesive")
		(11 "B.Adhes" user "B.Adhesive")
		(13 "F.Paste" user "Package Geometry/Pastemask Top")
		(15 "B.Paste" user "Package Geometry/Pastemask Bottom")
		(5 "F.SilkS" user "Ref Des/Silkscreen Top")
		(7 "B.SilkS" user "Ref Des/Silkscreen Bottom")
		(1 "F.Mask" user "Board Geometry/Soldermask Top")
		(3 "B.Mask" user "Board Geometry/Soldermask Bottom")
		(17 "Dwgs.User" user "User.Drawings")
		(19 "Cmts.User" user "User.Comments")
		(21 "Eco1.User" user "User.Eco1")
		(23 "Eco2.User" user "User.Eco2")
		(25 "Edge.Cuts" user "Board Geometry/Outline")
		(27 "Margin" user)
		(31 "F.CrtYd" user "Package Geometry/Place Bound Top")
		(29 "B.CrtYd" user "Package Geometry/Place Bound Bottom")
		(35 "F.Fab" user "Ref Des/Assembly Top")
		(33 "B.Fab" user "Ref Des/Assembly Bottom")
	)
	(footprint ""
		(layer "F.Cu")
		(at 45.907706 -120.403874 90)
		(property "Reference" "R765"
			(at 0 0 90)
			(layer "F.SilkS")
			(hide yes)
			(effects
				(font
					(size 1.27 1.27)
				)
			)
		)
		(property "Value" "0R2J-2-GP"
			(at 0.064008 -3.993896 90)
			(unlocked yes)
			(layer "F.Fab")
			(hide yes)
			(effects
				(font
					(size 1.016 1.016)
					(thickness 0.1524)
				)
			)
		)
		(property "Device Type" "R402H16"
			(at 0.064008 -5.517896 90)
			(unlocked yes)
			(layer "F.Fab")
			(hide yes)
			(effects
				(font
					(size 1.016 1.016)
					(thickness 0.1524)
				)
			)
		)
		(duplicate_pad_numbers_are_jumpers no)
		(fp_line
			(start 0.508 -0.9398)
			(end -0.508 -0.9398)
			(stroke
				(width 0.1524)
				(type default)
			)
			(layer "F.SilkS")
		)
		(fp_line
			(start -0.508 -0.9398)
			(end -0.508 0.9398)
			(stroke
				(width 0.1524)
				(type default)
			)
			(layer "F.SilkS")
		)
		(fp_rect
			(start -0.508 0.9398)
			(end 0.508 -0.9398)
			(stroke
				(width 0)
				(type default)
			)
			(fill no)
			(layer "F.CrtYd")
		)
		(fp_rect
			(start -0.508 0.9398)
			(end 0.508 -0.9398)
			(stroke
				(width 0)
				(type default)
			)
			(fill no)
			(layer "F.Fab")
		)
		(pad "1" smd custom
			(at 0 -0.4445 90)
			(size 0.1397 0.1397)
			(layers "F.Cu" "F.Mask" "F.Paste")
			(net "FLA0_SPI_RST")
			(options
				(clearance outline)
				(anchor circle)
			)
			(primitives
				(gr_poly
					(pts
						(arc
							(start -0.1778 -0.2794)
							(mid -0.249642 -0.249642)
							(end -0.2794 -0.1778)
						)
						(arc
							(start -0.2794 0.1778)
							(mid -0.249642 0.249642)
							(end -0.1778 0.2794)
						)
						(arc
							(start 0.1778 0.2794)
							(mid 0.249642 0.249642)
							(end 0.2794 0.1778)
						)
						(arc
							(start 0.2794 -0.1778)
							(mid 0.249642 -0.249642)
							(end 0.1778 -0.2794)
						)
					)
					(width 0)
					(fill yes)
				)
			)
		)
		(pad "2" smd custom
			(at 0 0.4445 90)
			(size 0.1397 0.1397)
			(layers "F.Cu" "F.Mask" "F.Paste")
			(net "RST_BMC_EXTRST_N")
			(options
				(clearance outline)
				(anchor circle)
			)
			(primitives
				(gr_poly
					(pts
						(arc
							(start -0.1778 -0.2794)
							(mid -0.249642 -0.249642)
							(end -0.2794 -0.1778)
						)
						(arc
							(start -0.2794 0.1778)
							(mid -0.249642 0.249642)
							(end -0.1778 0.2794)
						)
						(arc
							(start 0.1778 0.2794)
							(mid 0.249642 0.249642)
							(end 0.2794 0.1778)
						)
						(arc
							(start 0.2794 -0.1778)
							(mid 0.249642 -0.249642)
							(end 0.1778 -0.2794)
						)
					)
					(width 0)
					(fill yes)
				)
			)
		)
	)
	(footprint ""
		(layer "F.Cu")
		(at 70.2056 -162.756088 90)
		(property "Reference" "C52"
			(at 0 0 90)
			(layer "F.SilkS")
			(hide yes)
			(effects
				(font
					(size 1.27 1.27)
				)
			)
		)
		(property "Value" "SCD1U16V2KX-3GP"
			(at 1.1811 -2.7051 90)
			(unlocked yes)
			(layer "F.Fab")
			(hide yes)
			(effects
				(font
					(size 1.016 1.016)
					(thickness 0.1524)
				)
			)
		)
		(property "Device Type" "C402H22"
			(at 1.1811 -4.2291 90)
			(unlocked yes)
			(layer "F.Fab")
			(hide yes)
			(effects
				(font
					(size 1.016 1.016)
					(thickness 0.1524)
				)
			)
		)
		(duplicate_pad_numbers_are_jumpers no)
		(fp_rect
			(start -0.4318 0.9525)
			(end 0.4318 -0.9525)
			(stroke
				(width 0)
				(type default)
			)
			(fill no)
			(layer "F.CrtYd")
		)
		(fp_rect
			(start -0.4318 0.9525)
			(end 0.4318 -0.9525)
			(stroke
				(width 0)
				(type default)
			)
			(fill no)
			(layer "F.Fab")
		)
		(pad "1" smd custom
			(at 0 -0.4445 90)
			(size 0.1524 0.1524)
			(layers "F.Cu" "F.Mask" "F.Paste")
			(net "BMC_TPM_RST_N")
			(options
				(clearance outline)
				(anchor circle)
			)
			(primitives
				(gr_poly
					(pts
						(arc
							(start 0.3048 -0.2032)
							(mid 0.275042 -0.275042)
							(end 0.2032 -0.3048)
						)
						(arc
							(start -0.2032 -0.3048)
							(mid -0.275042 -0.275042)
							(end -0.3048 -0.2032)
						)
						(arc
							(start -0.3048 0.2032)
							(mid -0.275042 0.275042)
							(end -0.2032 0.3048)
						)
						(arc
							(start 0.2032 0.3048)
							(mid 0.275042 0.275042)
							(end 0.3048 0.2032)
						)
					)
					(width 0)
					(fill yes)
				)
			)
		)
		(pad "2" smd custom
			(at 0 0.4445 90)
			(size 0.1524 0.1524)
			(layers "F.Cu" "F.Mask" "F.Paste")
			(net "GND")
			(options
				(clearance outline)
				(anchor circle)
			)
			(primitives
				(gr_poly
					(pts
						(arc
							(start 0.3048 -0.2032)
							(mid 0.275042 -0.275042)
							(end 0.2032 -0.3048)
						)
						(arc
							(start -0.2032 -0.3048)
							(mid -0.275042 -0.275042)
							(end -0.3048 -0.2032)
						)
						(arc
							(start -0.3048 0.2032)
							(mid -0.275042 0.275042)
							(end -0.2032 0.3048)
						)
						(arc
							(start 0.2032 0.3048)
							(mid 0.275042 0.275042)
							(end 0.3048 0.2032)
						)
					)
					(width 0)
					(fill yes)
				)
			)
		)
	)
	(footprint ""
		(layer "F.Cu")
		(at 158.124398 -8.312404)
		(property "Reference" "C210"
			(at 0 0 0)
			(layer "F.SilkS")
			(hide yes)
			(effects
				(font
					(size 1.27 1.27)
				)
			)
		)
		(property "Value" "SC2200P50V2KX-2GP"
			(at 1.1811 -2.7051 0)
			(unlocked yes)
			(layer "F.Fab")
			(hide yes)
			(effects
				(font
					(size 1.016 1.016)
					(thickness 0.1524)
				)
			)
		)
		(property "Device Type" "C402H22"
			(at 1.1811 -4.2291 0)
			(unlocked yes)
			(layer "F.Fab")
			(hide yes)
			(effects
				(font
					(size 1.016 1.016)
					(thickness 0.1524)
				)
			)
		)
		(duplicate_pad_numbers_are_jumpers no)
		(fp_rect
			(start -0.4318 0.9525)
			(end 0.4318 -0.9525)
			(stroke
				(width 0)
				(type default)
			)
			(fill no)
			(layer "F.CrtYd")
		)
		(fp_rect
			(start -0.4318 0.9525)
			(end 0.4318 -0.9525)
			(stroke
				(width 0)
				(type default)
			)
			(fill no)
			(layer "F.Fab")
		)
		(pad "1" smd custom
			(at 0 -0.4445)
			(size 0.1524 0.1524)
			(layers "F.Cu" "F.Mask" "F.Paste")
			(net "P1V8_STBY_SW")
			(options
				(clearance outline)
				(anchor circle)
			)
			(primitives
				(gr_poly
					(pts
						(arc
							(start 0.3048 -0.2032)
							(mid 0.275042 -0.275042)
							(end 0.2032 -0.3048)
						)
						(arc
							(start -0.2032 -0.3048)
							(mid -0.275042 -0.275042)
							(end -0.3048 -0.2032)
						)
						(arc
							(start -0.3048 0.2032)
							(mid -0.275042 0.275042)
							(end -0.2032 0.3048)
						)
						(arc
							(start 0.2032 0.3048)
							(mid 0.275042 0.275042)
							(end 0.3048 0.2032)
						)
					)
					(width 0)
					(fill yes)
				)
			)
		)
		(pad "2" smd custom
			(at 0 0.4445)
			(size 0.1524 0.1524)
			(layers "F.Cu" "F.Mask" "F.Paste")
			(net "P1V8_STBY_SNB")
			(options
				(clearance outline)
				(anchor circle)
			)
			(primitives
				(gr_poly
					(pts
						(arc
							(start 0.3048 -0.2032)
							(mid 0.275042 -0.275042)
							(end 0.2032 -0.3048)
						)
						(arc
							(start -0.2032 -0.3048)
							(mid -0.275042 -0.275042)
							(end -0.3048 -0.2032)
						)
						(arc
							(start -0.3048 0.2032)
							(mid -0.275042 0.275042)
							(end -0.2032 0.3048)
						)
						(arc
							(start 0.2032 0.3048)
							(mid 0.275042 0.275042)
							(end 0.3048 0.2032)
						)
					)
					(width 0)
					(fill yes)
				)
			)
		)
	)
	(footprint ""
		(layer "F.Cu")
		(at 69.55028 -181.76748 -90)
		(property "Reference" "C201"
			(at 0 0 270)
			(layer "F.SilkS")
			(hide yes)
			(effects
				(font
					(size 1.27 1.27)
				)
			)
		)
		(property "Value" "SCD1U16V2KX-3GP"
			(at 1.1811 -2.7051 270)
			(unlocked yes)
			(layer "F.Fab")
			(hide yes)
			(effects
				(font
					(size 1.016 1.016)
					(thickness 0.1524)
				)
			)
		)
		(property "Device Type" "C402H22"
			(at 1.1811 -4.2291 270)
			(unlocked yes)
			(layer "F.Fab")
			(hide yes)
			(effects
				(font
					(size 1.016 1.016)
					(thickness 0.1524)
				)
			)
		)
		(duplicate_pad_numbers_are_jumpers no)
		(fp_rect
			(start -0.4318 0.9525)
			(end 0.4318 -0.9525)
			(stroke
				(width 0)
				(type default)
			)
			(fill no)
			(layer "F.CrtYd")
		)
		(fp_rect
			(start -0.4318 0.9525)
			(end 0.4318 -0.9525)
			(stroke
				(width 0)
				(type default)
			)
			(fill no)
			(layer "F.Fab")
		)
		(pad "1" smd custom
			(at 0 -0.4445 270)
			(size 0.1524 0.1524)
			(layers "F.Cu" "F.Mask" "F.Paste")
			(net "TPS74801_P2V5_STBY_EN")
			(options
				(clearance outline)
				(anchor circle)
			)
			(primitives
				(gr_poly
					(pts
						(arc
							(start 0.3048 -0.2032)
							(mid 0.275042 -0.275042)
							(end 0.2032 -0.3048)
						)
						(arc
							(start -0.2032 -0.3048)
							(mid -0.275042 -0.275042)
							(end -0.3048 -0.2032)
						)
						(arc
							(start -0.3048 0.2032)
							(mid -0.275042 0.275042)
							(end -0.2032 0.3048)
						)
						(arc
							(start 0.2032 0.3048)
							(mid 0.275042 0.275042)
							(end 0.3048 0.2032)
						)
					)
					(width 0)
					(fill yes)
				)
			)
		)
		(pad "2" smd custom
			(at 0 0.4445 270)
			(size 0.1524 0.1524)
			(layers "F.Cu" "F.Mask" "F.Paste")
			(net "GND")
			(options
				(clearance outline)
				(anchor circle)
			)
			(primitives
				(gr_poly
					(pts
						(arc
							(start 0.3048 -0.2032)
							(mid 0.275042 -0.275042)
							(end 0.2032 -0.3048)
						)
						(arc
							(start -0.2032 -0.3048)
							(mid -0.275042 -0.275042)
							(end -0.3048 -0.2032)
						)
						(arc
							(start -0.3048 0.2032)
							(mid -0.275042 0.275042)
							(end -0.2032 0.3048)
						)
						(arc
							(start 0.2032 0.3048)
							(mid 0.275042 0.275042)
							(end 0.3048 0.2032)
						)
					)
					(width 0)
					(fill yes)
				)
			)
		)
	)
	(footprint ""
		(layer "F.Cu")
		(at 30.3022 -131.2164)
		(property "Reference" "C79"
			(at 0 0 0)
			(layer "F.SilkS")
			(hide yes)
			(effects
				(font
					(size 1.27 1.27)
				)
			)
		)
		(property "Value" "SCD1U16V2KX-3GP"
			(at 1.1811 -2.7051 0)
			(unlocked yes)
			(layer "F.Fab")
			(hide yes)
			(effects
				(font
					(size 1.016 1.016)
					(thickness 0.1524)
				)
			)
		)
		(property "Device Type" "C402H22"
			(at 1.1811 -4.2291 0)
			(unlocked yes)
			(layer "F.Fab")
			(hide yes)
			(effects
				(font
					(size 1.016 1.016)
					(thickness 0.1524)
				)
			)
		)
		(duplicate_pad_numbers_are_jumpers no)
		(fp_rect
			(start -0.4318 0.9525)
			(end 0.4318 -0.9525)
			(stroke
				(width 0)
				(type default)
			)
			(fill no)
			(layer "F.CrtYd")
		)
		(fp_rect
			(start -0.4318 0.9525)
			(end 0.4318 -0.9525)
			(stroke
				(width 0)
				(type default)
			)
			(fill no)
			(layer "F.Fab")
		)
		(pad "1" smd custom
			(at 0 -0.4445)
			(size 0.1524 0.1524)
			(layers "F.Cu" "F.Mask" "F.Paste")
			(net "P3V3_STBY")
			(options
				(clearance outline)
				(anchor circle)
			)
			(primitives
				(gr_poly
					(pts
						(arc
							(start 0.3048 -0.2032)
							(mid 0.275042 -0.275042)
							(end 0.2032 -0.3048)
						)
						(arc
							(start -0.2032 -0.3048)
							(mid -0.275042 -0.275042)
							(end -0.3048 -0.2032)
						)
						(arc
							(start -0.3048 0.2032)
							(mid -0.275042 0.275042)
							(end -0.2032 0.3048)
						)
						(arc
							(start 0.2032 0.3048)
							(mid 0.275042 0.275042)
							(end 0.3048 0.2032)
						)
					)
					(width 0)
					(fill yes)
				)
			)
		)
		(pad "2" smd custom
			(at 0 0.4445)
			(size 0.1524 0.1524)
			(layers "F.Cu" "F.Mask" "F.Paste")
			(net "GND")
			(options
				(clearance outline)
				(anchor circle)
			)
			(primitives
				(gr_poly
					(pts
						(arc
							(start 0.3048 -0.2032)
							(mid 0.275042 -0.275042)
							(end 0.2032 -0.3048)
						)
						(arc
							(start -0.2032 -0.3048)
							(mid -0.275042 -0.275042)
							(end -0.3048 -0.2032)
						)
						(arc
							(start -0.3048 0.2032)
							(mid -0.275042 0.275042)
							(end -0.2032 0.3048)
						)
						(arc
							(start 0.2032 0.3048)
							(mid 0.275042 0.275042)
							(end 0.3048 0.2032)
						)
					)
					(width 0)
					(fill yes)
				)
			)
		)
	)
	(footprint ""
		(layer "F.Cu")
		(at 66.757042 -159.104584)
		(property "Reference" "R775"
			(at 0 0 0)
			(layer "F.SilkS")
			(hide yes)
			(effects
				(font
					(size 1.27 1.27)
				)
			)
		)
		(property "Value" "1KR2F-3-GP"
			(at 0.064008 -3.993896 0)
			(unlocked yes)
			(layer "F.Fab")
			(hide yes)
			(effects
				(font
					(size 1.016 1.016)
					(thickness 0.1524)
				)
			)
		)
		(property "Device Type" "R402H16"
			(at 0.064008 -5.517896 0)
			(unlocked yes)
			(layer "F.Fab")
			(hide yes)
			(effects
				(font
					(size 1.016 1.016)
					(thickness 0.1524)
				)
			)
		)
		(duplicate_pad_numbers_are_jumpers no)
		(fp_line
			(start -0.508 -0.9398)
			(end -0.508 0.9398)
			(stroke
				(width 0.1524)
				(type default)
			)
			(layer "F.SilkS")
		)
		(fp_line
			(start 0.508 -0.9398)
			(end -0.508 -0.9398)
			(stroke
				(width 0.1524)
				(type default)
			)
			(layer "F.SilkS")
		)
		(fp_rect
			(start -0.508 0.9398)
			(end 0.508 -0.9398)
			(stroke
				(width 0)
				(type default)
			)
			(fill no)
			(layer "F.CrtYd")
		)
		(fp_rect
			(start -0.508 0.9398)
			(end 0.508 -0.9398)
			(stroke
				(width 0)
				(type default)
			)
			(fill no)
			(layer "F.Fab")
		)
		(pad "1" smd custom
			(at 0 -0.4445)
			(size 0.1397 0.1397)
			(layers "F.Cu" "F.Mask" "F.Paste")
			(net "ADC_P1V15_STBY")
			(options
				(clearance outline)
				(anchor circle)
			)
			(primitives
				(gr_poly
					(pts
						(arc
							(start -0.1778 -0.2794)
							(mid -0.249642 -0.249642)
							(end -0.2794 -0.1778)
						)
						(arc
							(start -0.2794 0.1778)
							(mid -0.249642 0.249642)
							(end -0.1778 0.2794)
						)
						(arc
							(start 0.1778 0.2794)
							(mid 0.249642 0.249642)
							(end 0.2794 0.1778)
						)
						(arc
							(start 0.2794 -0.1778)
							(mid 0.249642 -0.249642)
							(end 0.1778 -0.2794)
						)
					)
					(width 0)
					(fill yes)
				)
			)
		)
		(pad "2" smd custom
			(at 0 0.4445)
			(size 0.1397 0.1397)
			(layers "F.Cu" "F.Mask" "F.Paste")
			(net "GND")
			(options
				(clearance outline)
				(anchor circle)
			)
			(primitives
				(gr_poly
					(pts
						(arc
							(start -0.1778 -0.2794)
							(mid -0.249642 -0.249642)
							(end -0.2794 -0.1778)
						)
						(arc
							(start -0.2794 0.1778)
							(mid -0.249642 0.249642)
							(end -0.1778 0.2794)
						)
						(arc
							(start 0.1778 0.2794)
							(mid 0.249642 0.249642)
							(end 0.2794 0.1778)
						)
						(arc
							(start 0.2794 -0.1778)
							(mid 0.249642 -0.249642)
							(end 0.1778 -0.2794)
						)
					)
					(width 0)
					(fill yes)
				)
			)
		)
	)
	(footprint ""
		(layer "F.Cu")
		(at 98.298 -172.6692 -90)
		(property "Reference" "R123"
			(at 0 0 270)
			(layer "F.SilkS")
			(hide yes)
			(effects
				(font
					(size 1.27 1.27)
				)
			)
		)
		(property "Value" "0R2J-2-GP"
			(at 0.064008 -3.993896 270)
			(unlocked yes)
			(layer "F.Fab")
			(hide yes)
			(effects
				(font
					(size 1.016 1.016)
					(thickness 0.1524)
				)
			)
		)
		(property "Device Type" "R402H16"
			(at 0.064008 -5.517896 270)
			(unlocked yes)
			(layer "F.Fab")
			(hide yes)
			(effects
				(font
					(size 1.016 1.016)
					(thickness 0.1524)
				)
			)
		)
		(duplicate_pad_numbers_are_jumpers no)
		(fp_line
			(start -0.508 -0.9398)
			(end -0.508 0.9398)
			(stroke
				(width 0.1524)
				(type default)
			)
			(layer "F.SilkS")
		)
		(fp_line
			(start 0.508 -0.9398)
			(end -0.508 -0.9398)
			(stroke
				(width 0.1524)
				(type default)
			)
			(layer "F.SilkS")
		)
		(fp_rect
			(start -0.508 0.9398)
			(end 0.508 -0.9398)
			(stroke
				(width 0)
				(type default)
			)
			(fill no)
			(layer "F.CrtYd")
		)
		(fp_rect
			(start -0.508 0.9398)
			(end 0.508 -0.9398)
			(stroke
				(width 0)
				(type default)
			)
			(fill no)
			(layer "F.Fab")
		)
		(pad "1" smd custom
			(at 0 -0.4445 270)
			(size 0.1397 0.1397)
			(layers "F.Cu" "F.Mask" "F.Paste")
			(net "I2C_DPB_MISC_SDA")
			(options
				(clearance outline)
				(anchor circle)
			)
			(primitives
				(gr_poly
					(pts
						(arc
							(start -0.1778 -0.2794)
							(mid -0.249642 -0.249642)
							(end -0.2794 -0.1778)
						)
						(arc
							(start -0.2794 0.1778)
							(mid -0.249642 0.249642)
							(end -0.1778 0.2794)
						)
						(arc
							(start 0.1778 0.2794)
							(mid 0.249642 0.249642)
							(end 0.2794 0.1778)
						)
						(arc
							(start 0.2794 -0.1778)
							(mid 0.249642 -0.249642)
							(end 0.1778 -0.2794)
						)
					)
					(width 0)
					(fill yes)
				)
			)
		)
		(pad "2" smd custom
			(at 0 0.4445 270)
			(size 0.1397 0.1397)
			(layers "F.Cu" "F.Mask" "F.Paste")
			(net "I2C_DPB_MISC_SDA_R")
			(options
				(clearance outline)
				(anchor circle)
			)
			(primitives
				(gr_poly
					(pts
						(arc
							(start -0.1778 -0.2794)
							(mid -0.249642 -0.249642)
							(end -0.2794 -0.1778)
						)
						(arc
							(start -0.2794 0.1778)
							(mid -0.249642 0.249642)
							(end -0.1778 0.2794)
						)
						(arc
							(start 0.1778 0.2794)
							(mid 0.249642 0.249642)
							(end 0.2794 0.1778)
						)
						(arc
							(start 0.2794 -0.1778)
							(mid 0.249642 -0.249642)
							(end 0.1778 -0.2794)
						)
					)
					(width 0)
					(fill yes)
				)
			)
		)
	)
)
